FILE_TYPE = CONNECTIVITY;
{Allegro Design Entry HDL 17.2-2016 S066 (3851973) 4/6/2020}
"PAGE_NUMBER" = 522;
0"NC";
1"SG\g";
2"SG\g";
3"XP3R3V\g";
4"XP3R3V\g";
5"SG\g";
6"SG\g";
7"SG\g";
8"SG\g";
9"CLK_200M_OE";
10"CLK_125M_OE";
11"VDD3V3_OSC_200M";
12"OSC_200M_CLKP";
13"MHZ200CLKP_CLKIN";
14"OSC_200M_CLKN";
15"MHZ200CLKN_CLKIN";
16"OSC_125M_CLKP";
17"OSC_125M_CLKN";
18"MHZ125CLKP_CLKIN";
19"MHZ125CLKN_CLKIN";
20"VDD3V3_OSC_125M";
%"CAPACITOR"
"1","(-6200,3000)","0","passive","I142";
;
$LOCATION"C254"
CDS_LOCATION"C254"
$SEC"1"
CDS_SEC"1"
PACKAGE"0402"
VOLTAGE"10V"
VALUE"0.1UF"
CDS_LIB"passive"
CDS_LMAN_SYM_OUTLINE"0,50,50,-50"
CLS_PN"G105-0B104-CK"
TOLERANCE"10%";
"2"
$PN"2"19;
"1"
$PN"1"17;
%"CAPACITOR"
"1","(-6200,3100)","0","passive","I143";
;
$LOCATION"C253"
CDS_LOCATION"C253"
$SEC"1"
CDS_SEC"1"
VALUE"0.1UF"
PACKAGE"0402"
VOLTAGE"10V"
CDS_LIB"passive"
CDS_LMAN_SYM_OUTLINE"0,50,50,-50"
CLS_PN"G105-0B104-CK"
TOLERANCE"10%";
"2"
$PN"2"18;
"1"
$PN"1"16;
%"OSC6P_V2"
"1","(-8750,6750)","0","clock","I144";
;
$LOCATION"Y3"
CDS_LOCATION"Y3"
$SEC"1"
CDS_SEC"1"
PART_NUMBER"LMK62A2-200M00SIAR"
CLS_PN"A130-00003-AW"
CDS_LIB"clock"
CDS_LMAN_SYM_OUTLINE"0,0,600,-500";
"VDD"
$PN"6"11;
"GND"
$PN"3"1;
"OUT_N"
$PN"5"14;
"OUT_P"
$PN"4"12;
"NC"
$PN"2"0;
"OE"
$PN"1"9;
%"OSC6P_V2"
"1","(-8750,3200)","0","clock","I145";
;
$LOCATION"Y4"
CDS_LOCATION"Y4"
$SEC"1"
CDS_SEC"1"
CLS_PN"A130-00004-AW"
PART_NUMBER"LMK61A2-125M00SIAR"
CDS_LIB"clock"
CDS_LMAN_SYM_OUTLINE"0,0,600,-500";
"VDD"
$PN"6"20;
"GND"
$PN"3"2;
"OUT_N"
$PN"5"17;
"OUT_P"
$PN"4"16;
"NC"
$PN"2"0;
"OE"
$PN"1"10;
%"FERRITEBEAD"
"1","(-11050,6700)","2","passive","I146";
;
$LOCATION"L14"
CDS_LOCATION"L14"
$SEC"1"
CDS_SEC"1"
PACKAGE"0603"
VALUE"600OHM"
DCR"1300MA 0.15OHM"
TOLERANCE"25%"
CLS_PN"G191-10097-01"
CDS_LIB"passive"
CDS_LMAN_SYM_OUTLINE"0,0,200,-100";
"2"
$PN"2"3;
"1"
$PN"1"11;
%"CAPACITOR"
"2","(-10200,6350)","2","passive","I147";
;
$LOCATION"C248"
CDS_LOCATION"C248"
$SEC"1"
CDS_SEC"1"
VALUE"0.1UF"
VOLTAGE"25V"
PACKAGE"0402"
TOLERANCE"10%"
CLS_PN"G105-0B104-EK"
CDS_LMAN_SYM_OUTLINE"-50,0,50,-50"
CDS_LIB"passive";
"2"
$PN"2"8;
"1"
$PN"1"11;
%"RESISTOR"
"1","(-9400,6450)","0","passive","I149";
;
$LOCATION"R235"
CDS_LOCATION"R235"
$SEC"1"
CDS_SEC"1"
VALUE"4.7KOHM"
PACKAGE"0402"
TOLERANCE"1%"
CDS_LIB"passive"
CDS_LMAN_SYM_OUTLINE"-50,50,100,-50"
CLS_PN"G155-14701-01";
"1"
$PN"1"11;
"2"
$PN"2"9;
%"GND_SG"
"1","(-10150,5800)","2","cls","I150";
;
HDL_POWER"SG"
CDS_LMAN_SYM_OUTLINE"0,0,100,-50"
CDS_LIB"cls"
BODY_TYPE"PLUMBING";
"SGND"8;
%"CAPACITOR"
"2","(-10650,6350)","2","passive","I151";
;
$LOCATION"C246"
CDS_LOCATION"C246"
$SEC"1"
CDS_SEC"1"
PACKAGE"0402"
VOLTAGE"6.3V"
VALUE"10UF"
CDS_LIB"passive"
CDS_LMAN_SYM_OUTLINE"-50,0,50,-50"
CLS_PN"G105-0C106-BM"
TOLERANCE"20%";
"2"
$PN"2"8;
"1"
$PN"1"11;
%"CAPACITOR"
"2","(-11650,6350)","2","passive","I152";
;
$LOCATION"C244"
CDS_LOCATION"C244"
$SEC"1"
CDS_SEC"1"
VALUE"0.1UF"
VOLTAGE"25V"
PACKAGE"0402"
CDS_LIB"passive"
CDS_LMAN_SYM_OUTLINE"-50,0,50,-50"
CLS_PN"G105-0B104-EK"
TOLERANCE"10%";
"2"
$PN"2"8;
"1"
$PN"1"3;
%"CAPACITOR"
"2","(-11650,2800)","2","passive","I153";
;
$LOCATION"C245"
CDS_LOCATION"C245"
$SEC"1"
CDS_SEC"1"
VALUE"0.1UF"
PACKAGE"0402"
VOLTAGE"25V"
CLS_PN"G105-0B104-EK"
CDS_LMAN_SYM_OUTLINE"-50,0,50,-50"
CDS_LIB"passive"
TOLERANCE"10%";
"2"
$PN"2"7;
"1"
$PN"1"4;
%"CAPACITOR"
"2","(-10650,2800)","2","passive","I154";
;
$LOCATION"C247"
CDS_LOCATION"C247"
$SEC"1"
CDS_SEC"1"
VOLTAGE"6.3V"
VALUE"10UF"
PACKAGE"0402"
TOLERANCE"20%"
CDS_LIB"passive"
CDS_LMAN_SYM_OUTLINE"-50,0,50,-50"
CLS_PN"G105-0C106-BM";
"2"
$PN"2"7;
"1"
$PN"1"20;
%"GND_SG"
"1","(-10150,2250)","2","cls","I155";
;
HDL_POWER"SG"
CDS_LMAN_SYM_OUTLINE"0,0,100,-50"
CDS_LIB"cls"
BODY_TYPE"PLUMBING";
"SGND"7;
%"RESISTOR"
"1","(-9350,2900)","0","passive","I156";
;
$LOCATION"R236"
CDS_LOCATION"R236"
$SEC"1"
CDS_SEC"1"
PACKAGE"0402"
VALUE"4.7KOHM"
CLS_PN"G155-14701-01"
CDS_LMAN_SYM_OUTLINE"-50,50,100,-50"
CDS_LIB"passive"
TOLERANCE"1%";
"1"
$PN"1"20;
"2"
$PN"2"10;
%"CAPACITOR"
"2","(-10200,2820)","2","passive","I158";
;
$LOCATION"C249"
CDS_LOCATION"C249"
$SEC"1"
CDS_SEC"1"
VALUE"0.1UF"
PACKAGE"0402"
VOLTAGE"25V"
CLS_PN"G105-0B104-EK"
CDS_LMAN_SYM_OUTLINE"-50,0,50,-50"
CDS_LIB"passive"
TOLERANCE"10%";
"2"
$PN"2"7;
"1"
$PN"1"20;
%"FERRITEBEAD"
"1","(-11050,3150)","2","passive","I159";
;
$LOCATION"L10"
CDS_LOCATION"L10"
$SEC"1"
CDS_SEC"1"
DCR"1300MA 0.15OHM"
VALUE"600OHM"
PACKAGE"0603"
CLS_PN"G191-10097-01"
CDS_LIB"passive"
CDS_LMAN_SYM_OUTLINE"0,0,200,-100"
TOLERANCE"25%";
"2"
$PN"2"4;
"1"
$PN"1"20;
%"CAPACITOR"
"1","(-6150,6550)","0","passive","I160";
;
$LOCATION"C252"
CDS_LOCATION"C252"
$SEC"1"
CDS_SEC"1"
PACKAGE"0402"
VOLTAGE"10V"
VALUE"0.1UF"
TOLERANCE"10%"
CDS_LIB"passive"
CDS_LMAN_SYM_OUTLINE"0,50,50,-50"
CLS_PN"G105-0B104-CK";
"2"
$PN"2"15;
"1"
$PN"1"14;
%"CAPACITOR"
"1","(-6150,6650)","0","passive","I161";
;
$LOCATION"C251"
CDS_LOCATION"C251"
$SEC"1"
CDS_SEC"1"
PACKAGE"0402"
VALUE"0.1UF"
VOLTAGE"10V"
TOLERANCE"10%"
CDS_LIB"passive"
CDS_LMAN_SYM_OUTLINE"0,50,50,-50"
CLS_PN"G105-0B104-CK";
"2"
$PN"2"13;
"1"
$PN"1"12;
%"GND_SG"
"1","(-8000,2400)","0","cls","I167";
;
HDL_POWER"SG"
CDS_LMAN_SYM_OUTLINE"0,0,100,-50"
CDS_LIB"cls"
BODY_TYPE"PLUMBING";
"SGND"2;
%"GND_SG"
"1","(-8000,5950)","0","cls","I168";
;
HDL_POWER"SG"
CDS_LIB"cls"
CDS_LMAN_SYM_OUTLINE"0,0,100,-50"
BODY_TYPE"PLUMBING";
"SGND"1;
%"RESISTOR"
"1","(-7000,6150)","5","passive","I169";
;
$LOCATION"R239"
CDS_LOCATION"R239"
$SEC"1"
CDS_SEC"1"
VALUE"150OHM"
PACKAGE"0402"
NO_ASSY"TRUE"
CLS_PN"G155-11500-01"
CDS_LIB"passive"
CDS_LMAN_SYM_OUTLINE"-50,50,100,-50"
TOLERANCE"1%";
"1"
$PN"1"14;
"2"
$PN"2"6;
%"RESISTOR"
"1","(-6650,6150)","5","passive","I170";
;
$LOCATION"R241"
CDS_LOCATION"R241"
$SEC"1"
CDS_SEC"1"
PACKAGE"0402"
VALUE"150OHM"
NO_ASSY"TRUE"
CLS_PN"G155-11500-01"
CDS_LIB"passive"
CDS_LMAN_SYM_OUTLINE"-50,50,100,-50"
TOLERANCE"1%";
"1"
$PN"1"12;
"2"
$PN"2"6;
%"GND_SG"
"1","(-7050,5700)","0","cls","I171";
;
HDL_POWER"SG"
CDS_LIB"cls"
CDS_LMAN_SYM_OUTLINE"0,0,100,-50"
BODY_TYPE"PLUMBING";
"SGND"6;
%"RESISTOR"
"1","(-7000,2600)","5","passive","I172";
;
$LOCATION"R240"
CDS_LOCATION"R240"
$SEC"1"
CDS_SEC"1"
NO_ASSY"TRUE"
PACKAGE"0402"
VALUE"150OHM"
CLS_PN"G155-11500-01"
CDS_LMAN_SYM_OUTLINE"-50,50,100,-50"
CDS_LIB"passive"
TOLERANCE"1%";
"1"
$PN"1"17;
"2"
$PN"2"5;
%"GND_SG"
"1","(-7050,2150)","0","cls","I173";
;
HDL_POWER"SG"
CDS_LMAN_SYM_OUTLINE"0,0,100,-50"
CDS_LIB"cls"
BODY_TYPE"PLUMBING";
"SGND"5;
%"RESISTOR"
"1","(-6650,2600)","5","passive","I174";
;
$LOCATION"R242"
CDS_LOCATION"R242"
$SEC"1"
CDS_SEC"1"
NO_ASSY"TRUE"
PACKAGE"0402"
VALUE"150OHM"
CLS_PN"G155-11500-01"
CDS_LMAN_SYM_OUTLINE"-50,50,100,-50"
CDS_LIB"passive"
TOLERANCE"1%";
"1"
$PN"1"16;
"2"
$PN"2"5;
%"VCC"
"1","(-11950,3300)","0","cls","I176";
;
VOLTAGE"3.3"
HDL_POWER"XP3R3V"
CDS_LIB"cls"
CDS_LMAN_SYM_OUTLINE"-250,250,250,-250"
BODY_TYPE"PLUMBING";
"$PIN0"4;
%"VCC"
"1","(-11950,6850)","0","cls","I177";
;
VOLTAGE"3.3"
HDL_POWER"XP3R3V"
CDS_LMAN_SYM_OUTLINE"-250,250,250,-250"
CDS_LIB"cls"
BODY_TYPE"PLUMBING";
"$PIN0"3;
END.
